# S9S_MB_2U (Grand Teton) — schematic netlist excerpt (pin names and nets, part order shuffled) for the footprints in the layout excerpt that follows; sources: Cadence DE-HDL packaged netlist, KiCad conversion of 03242023_DA0F0TMBIJ0_F0T_Motherboard_J_brd_V01_OCP.brd

PC191_P0_1  Q_CAP  1UF 16V 10% X6S  pkg C0402  page 275 : A = SW_P12V_PVCCINFAON_CPU0_FLT ; B = GND

U235  PCA9617ADP  IC  pkg TSSOP8_3XB  page 238
  VCCA  = P3V3_AUX
  SCLA  = SMB_OCP_V3_2_3V3AUX_SCL
  SDAA  = SMB_OCP_V3_2_3V3AUX_SDA
  GND  = GND
  EN  = HP_LVC3_OCP_V3_2_R_EN
  SDAB  = SMB_OCP_V3_2_3V3AUX_BUF_SDA
  SCLB  = SMB_OCP_V3_2_3V3AUX_BUF_SCL
  VCCB  = P3V3_OCP_V3_2

(kicad_pcb
	(version 20260206)
	(generator "pcbnew")
	(generator_version "10.0")
	(general
		(thickness 1.6)
		(legacy_teardrops no)
	)
	(paper "A4")
	(title_block
		(title "03242023_DA0F0TMBIJ0_F0T_Motherboard_J_brd_V01_OCP.brd")
		(comment 1 "Grand Teton / footprints 1538-1539 of 6105")
	)
	(layers
		(0 "F.Cu" signal "TOP")
		(4 "In1.Cu" signal "GND")
		(6 "In2.Cu" signal "IN1")
		(8 "In3.Cu" signal "GND1")
		(10 "In4.Cu" signal "IN2")
		(12 "In5.Cu" signal "GND2")
		(14 "In6.Cu" signal "IN3")
		(16 "In7.Cu" signal "GND3")
		(18 "In8.Cu" signal "VCC")
		(20 "In9.Cu" signal "VCC1")
		(22 "In10.Cu" signal "GND4")
		(24 "In11.Cu" signal "IN4")
		(26 "In12.Cu" signal "GND5")
		(28 "In13.Cu" signal "IN5")
		(30 "In14.Cu" signal "GND6")
		(32 "In15.Cu" signal "IN6")
		(34 "In16.Cu" signal "GND7")
		(2 "B.Cu" signal "BOTTOM")
		(9 "F.Adhes" user "F.Adhesive")
		(11 "B.Adhes" user "B.Adhesive")
		(13 "F.Paste" user "Package Geometry/Pastemask Top")
		(15 "B.Paste" user "Package Geometry/Pastemask Bottom")
		(5 "F.SilkS" user "Ref Des/Silkscreen Top")
		(7 "B.SilkS" user "Ref Des/Silkscreen Bottom")
		(1 "F.Mask" user "Board Geometry/Soldermask Top")
		(3 "B.Mask" user "Board Geometry/Soldermask Bottom")
		(17 "Dwgs.User" user "User.Drawings")
		(19 "Cmts.User" user "User.Comments")
		(21 "Eco1.User" user "User.Eco1")
		(23 "Eco2.User" user "User.Eco2")
		(25 "Edge.Cuts" user "Board Geometry/Outline")
		(27 "Margin" user)
		(31 "F.CrtYd" user "Package Geometry/Place Bound Top")
		(29 "B.CrtYd" user "Package Geometry/Place Bound Bottom")
		(35 "F.Fab" user "Ref Des/Assembly Top")
		(33 "B.Fab" user "Ref Des/Assembly Bottom")
	)
	(footprint ""
		(layer "F.Cu")
		(at 420.124128 -166.499286 -90)
		(property "Reference" "PC191_P0_1"
			(at 0 0 270)
			(layer "F.SilkS")
			(hide yes)
			(effects
				(font
					(size 1.27 1.27)
				)
			)
		)
		(property "Value" ""
			(at 0 0 270)
			(layer "F.Fab")
			(effects
				(font
					(size 1.27 1.27)
				)
			)
		)
		(duplicate_pad_numbers_are_jumpers no)
		(fp_line
			(start -0.7874 0.4064)
			(end -0.7874 -0.4064)
			(stroke
				(width 0.1524)
				(type default)
			)
			(layer "F.SilkS")
		)
		(fp_line
			(start 0.7874 0.4064)
			(end -0.7874 0.4064)
			(stroke
				(width 0.1524)
				(type default)
			)
			(layer "F.SilkS")
		)
		(fp_line
			(start -0.7874 -0.4064)
			(end 0.7874 -0.4064)
			(stroke
				(width 0.1524)
				(type default)
			)
			(layer "F.SilkS")
		)
		(fp_line
			(start 0.7874 -0.4064)
			(end 0.7874 0.4064)
			(stroke
				(width 0.1524)
				(type default)
			)
			(layer "F.SilkS")
		)
		(fp_line
			(start -0.67945 0.3048)
			(end -0.67945 -0.305054)
			(stroke
				(width 0.1)
				(type default)
			)
			(layer "F.Fab")
		)
		(fp_line
			(start -0.12065 0.3048)
			(end -0.67945 0.3048)
			(stroke
				(width 0.1)
				(type default)
			)
			(layer "F.Fab")
		)
		(fp_line
			(start 0.120396 0.3048)
			(end 0.120396 0.2794)
			(stroke
				(width 0.1)
				(type default)
			)
			(layer "F.Fab")
		)
		(fp_line
			(start 0.67945 0.3048)
			(end 0.120396 0.3048)
			(stroke
				(width 0.1)
				(type default)
			)
			(layer "F.Fab")
		)
		(fp_line
			(start -0.12065 0.2794)
			(end -0.12065 0.3048)
			(stroke
				(width 0.1)
				(type default)
			)
			(layer "F.Fab")
		)
		(fp_line
			(start 0.120396 0.2794)
			(end -0.12065 0.2794)
			(stroke
				(width 0.1)
				(type default)
			)
			(layer "F.Fab")
		)
		(fp_line
			(start -0.12065 -0.2794)
			(end 0.12065 -0.2794)
			(stroke
				(width 0.1)
				(type default)
			)
			(layer "F.Fab")
		)
		(fp_line
			(start 0.12065 -0.2794)
			(end 0.12065 -0.3048)
			(stroke
				(width 0.1)
				(type default)
			)
			(layer "F.Fab")
		)
		(fp_line
			(start 0.12065 -0.3048)
			(end 0.67945 -0.3048)
			(stroke
				(width 0.1)
				(type default)
			)
			(layer "F.Fab")
		)
		(fp_line
			(start 0.67945 -0.3048)
			(end 0.67945 0.3048)
			(stroke
				(width 0.1)
				(type default)
			)
			(layer "F.Fab")
		)
		(fp_line
			(start -0.67945 -0.305054)
			(end -0.12065 -0.305054)
			(stroke
				(width 0.1)
				(type default)
			)
			(layer "F.Fab")
		)
		(fp_line
			(start -0.12065 -0.305054)
			(end -0.12065 -0.2794)
			(stroke
				(width 0.1)
				(type default)
			)
			(layer "F.Fab")
		)
		(pad "1" smd circle
			(at -0.40005 0 270)
			(size 0 0)
			(layers "F.Cu" "F.Mask" "F.Paste")
			(net "SW_P12V_PVCCINFAON_CPU0_FLT")
		)
		(pad "2" smd circle
			(at 0.40005 0 270)
			(size 0 0)
			(layers "F.Cu" "F.Mask" "F.Paste")
			(net "GND")
		)
	)
	(footprint ""
		(layer "F.Cu")
		(at 103.85552 -31.731458 180)
		(property "Reference" "U235"
			(at 1.59766 -2.717292 0)
			(unlocked yes)
			(layer "F.SilkS")
			(effects
				(font
					(size 0.7874 0.5842)
					(thickness 0.1524)
				)
				(justify left)
			)
		)
		(property "Value" ""
			(at 0 0 180)
			(layer "F.Fab")
			(effects
				(font
					(size 1.27 1.27)
				)
			)
		)
		(duplicate_pad_numbers_are_jumpers no)
		(fp_line
			(start 1.463548 1.549908)
			(end -1.463548 1.549908)
			(stroke
				(width 0.1524)
				(type default)
			)
			(layer "F.SilkS")
		)
		(fp_line
			(start 1.463548 -1.549908)
			(end 1.463548 1.549908)
			(stroke
				(width 0.1524)
				(type default)
			)
			(layer "F.SilkS")
		)
		(fp_line
			(start 0.762 -1.549908)
			(end 1.463548 -1.549908)
			(stroke
				(width 0.1524)
				(type default)
			)
			(layer "F.SilkS")
		)
		(fp_line
			(start 0 -0.762)
			(end 0.762 -1.549908)
			(stroke
				(width 0.1524)
				(type default)
			)
			(layer "F.SilkS")
		)
		(fp_line
			(start -0.787908 -1.549908)
			(end 0 -0.762)
			(stroke
				(width 0.1524)
				(type default)
			)
			(layer "F.SilkS")
		)
		(fp_line
			(start -1.463548 1.549908)
			(end -1.463548 -1.549908)
			(stroke
				(width 0.1524)
				(type default)
			)
			(layer "F.SilkS")
		)
		(fp_line
			(start -1.463548 -1.549908)
			(end -0.787908 -1.549908)
			(stroke
				(width 0.1524)
				(type default)
			)
			(layer "F.SilkS")
		)
		(fp_poly
			(pts
				(xy -2.84988 -1.050036) (xy -3.46964 -0.740156) (xy -3.46964 -1.359916)
			)
			(stroke
				(width 0)
				(type default)
			)
			(fill yes)
			(layer "F.SilkS")
		)
		(fp_line
			(start 1.549908 1.549908)
			(end -1.549908 1.549908)
			(stroke
				(width 0.1)
				(type default)
			)
			(layer "F.Fab")
		)
		(fp_line
			(start 1.549908 -1.549908)
			(end 1.549908 1.549908)
			(stroke
				(width 0.1)
				(type default)
			)
			(layer "F.Fab")
		)
		(fp_line
			(start -1.549908 1.549908)
			(end -1.549908 -1.549908)
			(stroke
				(width 0.1)
				(type default)
			)
			(layer "F.Fab")
		)
		(fp_line
			(start -1.549908 -1.549908)
			(end 1.549908 -1.549908)
			(stroke
				(width 0.1)
				(type default)
			)
			(layer "F.Fab")
		)
		(fp_poly
			(pts
				(xy -3.4798 -1.359916) (xy -2.86004 -1.050036) (xy -3.4798 -0.740156)
			)
			(stroke
				(width 0)
				(type default)
			)
			(fill yes)
			(layer "F.Fab")
		)
		(pad "1" smd rect
			(at -2.175002 -1.050036 270)
			(size 0.6096 1.1684)
			(layers "F.Cu" "F.Mask" "F.Paste")
			(net "P3V3_AUX")
		)
		(pad "2" smd rect
			(at -2.175002 -0.32512 270)
			(size 0.4318 1.1684)
			(layers "F.Cu" "F.Mask" "F.Paste")
			(net "SMB_OCP_V3_2_3V3AUX_SCL")
		)
		(pad "3" smd rect
			(at -2.175002 0.32512 270)
			(size 0.4318 1.1684)
			(layers "F.Cu" "F.Mask" "F.Paste")
			(net "SMB_OCP_V3_2_3V3AUX_SDA")
		)
		(pad "4" smd rect
			(at -2.175002 1.050036 270)
			(size 0.6096 1.1684)
			(layers "F.Cu" "F.Mask" "F.Paste")
			(net "GND")
		)
		(pad "5" smd rect
			(at 2.175002 1.050036 270)
			(size 0.6096 1.1684)
			(layers "F.Cu" "F.Mask" "F.Paste")
			(net "HP_LVC3_OCP_V3_2_R_EN")
		)
		(pad "6" smd rect
			(at 2.175002 0.32512 270)
			(size 0.4318 1.1684)
			(layers "F.Cu" "F.Mask" "F.Paste")
			(net "SMB_OCP_V3_2_3V3AUX_BUF_SDA")
		)
		(pad "7" smd rect
			(at 2.175002 -0.32512 270)
			(size 0.4318 1.1684)
			(layers "F.Cu" "F.Mask" "F.Paste")
			(net "SMB_OCP_V3_2_3V3AUX_BUF_SCL")
		)
		(pad "8" smd rect
			(at 2.175002 -1.050036 270)
			(size 0.6096 1.1684)
			(layers "F.Cu" "F.Mask" "F.Paste")
			(net "P3V3_OCP_V3_2")
		)
	)
)
